(kicad_pcb
	(version 20260206)
	(generator "pcbnew")
	(generator_version "10.0")
	(general
		(thickness 1.6)
		(legacy_teardrops no)
	)
	(paper "A4")
	(title_block
		(title "v2-tray-backplane — ms_tbp_v2.brd")
		(comment 1 "Open CloudServer (Microsoft) / footprints 132-139 of 164")
	)
	(layers
		(0 "F.Cu" signal "TOP")
		(4 "In1.Cu" signal "LYR2")
		(6 "In2.Cu" signal "LYR3")
		(8 "In3.Cu" signal "LYR4")
		(10 "In4.Cu" signal "LYR5")
		(12 "In5.Cu" signal "LYR6")
		(14 "In6.Cu" signal "LYR7")
		(2 "B.Cu" signal "BOTTOM")
		(9 "F.Adhes" user "F.Adhesive")
		(11 "B.Adhes" user "B.Adhesive")
		(13 "F.Paste" user "Package Geometry/Pastemask Top")
		(15 "B.Paste" user "Package Geometry/Pastemask Bottom")
		(5 "F.SilkS" user "Ref Des/Silkscreen Top")
		(7 "B.SilkS" user "Ref Des/Silkscreen Bottom")
		(1 "F.Mask" user "Board Geometry/Soldermask Top")
		(3 "B.Mask" user "Board Geometry/Soldermask Bottom")
		(17 "Dwgs.User" user "User.Drawings")
		(19 "Cmts.User" user "User.Comments")
		(21 "Eco1.User" user "User.Eco1")
		(23 "Eco2.User" user "User.Eco2")
		(25 "Edge.Cuts" user "Board Geometry/Outline")
		(27 "Margin" user)
		(31 "F.CrtYd" user "Package Geometry/Place Bound Top")
		(29 "B.CrtYd" user "Package Geometry/Place Bound Bottom")
		(35 "F.Fab" user "Ref Des/Assembly Top")
		(33 "B.Fab" user "Ref Des/Assembly Bottom")
	)
	(footprint ""
		(layer "F.Cu")
		(at -95.25 39.010001 180)
		(property "Reference" "J21"
			(at -8.79094 -8.843599 0)
			(unlocked yes)
			(layer "F.SilkS")
			(effects
				(font
					(size 0.762 0.5334)
					(thickness 0.1016)
				)
			)
		)
		(property "Value" ""
			(at 0 0 180)
			(layer "F.Fab")
			(effects
				(font
					(size 1.27 1.27)
				)
			)
		)
		(duplicate_pad_numbers_are_jumpers no)
		(fp_line
			(start 9.874999 50.85)
			(end 9.874999 34.000001)
			(stroke
				(width 0.127)
				(type default)
			)
			(layer "F.SilkS")
		)
		(fp_line
			(start 9.874999 25.000001)
			(end 9.874999 32)
			(stroke
				(width 0.127)
				(type default)
			)
			(layer "F.SilkS")
		)
		(fp_line
			(start 9.874999 16.000001)
			(end 9.874999 23)
			(stroke
				(width 0.127)
				(type default)
			)
			(layer "F.SilkS")
		)
		(fp_line
			(start 9.874999 7.000002)
			(end 9.874999 14)
			(stroke
				(width 0.127)
				(type default)
			)
			(layer "F.SilkS")
		)
		(fp_line
			(start 9.874999 -3.75)
			(end 9.874999 5)
			(stroke
				(width 0.127)
				(type default)
			)
			(layer "F.SilkS")
		)
		(fp_line
			(start -9.874999 50.85)
			(end 9.874999 50.85)
			(stroke
				(width 0.127)
				(type default)
			)
			(layer "F.SilkS")
		)
		(fp_line
			(start -9.874999 38.499999)
			(end -9.874999 50.85)
			(stroke
				(width 0.127)
				(type default)
			)
			(layer "F.SilkS")
		)
		(fp_line
			(start -9.874999 36.500001)
			(end -9.874999 29.5)
			(stroke
				(width 0.127)
				(type default)
			)
			(layer "F.SilkS")
		)
		(fp_line
			(start -9.874999 27.500001)
			(end -9.874999 20.5)
			(stroke
				(width 0.127)
				(type default)
			)
			(layer "F.SilkS")
		)
		(fp_line
			(start -9.874999 18.500001)
			(end -9.874999 11.5)
			(stroke
				(width 0.127)
				(type default)
			)
			(layer "F.SilkS")
		)
		(fp_line
			(start -9.874999 9.499999)
			(end -9.874999 0.750001)
			(stroke
				(width 0.127)
				(type default)
			)
			(layer "F.SilkS")
		)
		(fp_line
			(start -9.874999 -2.264999)
			(end -9.874999 -7.869999)
			(stroke
				(width 0.127)
				(type default)
			)
			(layer "F.SilkS")
		)
		(fp_line
			(start -9.874999 -7.869999)
			(end -6.074999 -7.869999)
			(stroke
				(width 0.127)
				(type default)
			)
			(layer "F.SilkS")
		)
		(fp_poly
			(pts
				(arc
					(start -4.199999 37.600001)
					(mid -9.703758 42.804115)
					(end -14.807001 37.2067)
				)
				(arc
					(start -14.807001 -0.1848)
					(mid -14.550292 -1.881885)
					(end -13.7654 -3.408299)
				)
				(arc
					(start -9.7682 -10.080899)
					(mid -7.846041 -12.229854)
					(end -5.084 -13.056799)
				)
				(arc
					(start -5.0811 -13.056799)
					(mid -4.99375 -13.057419)
					(end -4.906401 -13.0566)
				)
				(arc
					(start 1.8942 -13.048599)
					(mid 3.117342 -12.977539)
					(end 4.291599 -12.627899)
				)
				(arc
					(start 10.9939 -9.842799)
					(mid 11.536623 -9.651121)
					(end 12.055399 -9.4018)
				)
				(arc
					(start 12.0555 -9.401701)
					(mid 14.088517 -7.41727)
					(end 14.8068 -4.668598)
				)
				(arc
					(start 14.8068 32.7031)
					(mid 10.110545 38.317137)
					(end 4.199999 34.000001)
				)
				(xy 4.199999 -2.5) (xy -4.199999 -2.5)
			)
			(stroke
				(width 0)
				(type default)
			)
			(fill no)
			(layer "B.CrtYd")
		)
		(fp_poly
			(pts
				(xy -10.875 51.850001)
				(arc
					(start -10.875 38.564599)
					(mid -11.270016 37.45)
					(end -10.875 36.335401)
				)
				(arc
					(start -10.875 29.5646)
					(mid -11.270017 28.450001)
					(end -10.875 27.335402)
				)
				(arc
					(start -10.875 20.5646)
					(mid -11.270017 19.449999)
					(end -10.875 18.335399)
				)
				(arc
					(start -10.875 11.5646)
					(mid -11.270016 10.45)
					(end -10.875 9.335399)
				)
				(arc
					(start -10.875 0.864601)
					(mid -11.270016 -0.249999)
					(end -10.875 -1.364599)
				)
				(xy -10.875 -8.87)
				(arc
					(start -6.370599 -8.87)
					(mid -5 -9.520011)
					(end -3.629401 -8.87)
				)
				(arc
					(start 0.829399 -8.87)
					(mid 2.2 -9.520014)
					(end 3.5706 -8.87)
				)
				(xy 10.875 -8.87)
				(arc
					(start 10.875 -5.864601)
					(mid 11.270017 -4.75)
					(end 10.875 -3.6354)
				)
				(arc
					(start 10.875 4.835401)
					(mid 11.270016 5.950001)
					(end 10.875 7.064601)
				)
				(arc
					(start 10.875 13.835401)
					(mid 11.270016 14.950001)
					(end 10.875 16.064601)
				)
				(arc
					(start 10.875 22.8354)
					(mid 11.270017 23.950001)
					(end 10.875 25.064601)
				)
				(arc
					(start 10.875 31.8354)
					(mid 11.270016 32.95)
					(end 10.875 34.064601)
				)
				(xy 10.875 51.850001)
			)
			(stroke
				(width 0)
				(type default)
			)
			(fill no)
			(layer "F.CrtYd")
		)
		(fp_line
			(start 9.874999 50.85)
			(end 9.874999 -7.869999)
			(stroke
				(width 0.1)
				(type default)
			)
			(layer "F.Fab")
		)
		(fp_line
			(start 9.874999 -7.869999)
			(end -9.874999 -7.869999)
			(stroke
				(width 0.1)
				(type default)
			)
			(layer "F.Fab")
		)
		(fp_line
			(start -9.874999 50.85)
			(end 9.874999 50.85)
			(stroke
				(width 0.1)
				(type default)
			)
			(layer "F.Fab")
		)
		(fp_line
			(start -9.874999 -7.869999)
			(end -9.874999 50.85)
			(stroke
				(width 0.1)
				(type default)
			)
			(layer "F.Fab")
		)
		(pad "1" thru_hole circle
			(at -9.499999 -0.25 270)
			(size 1.5494 1.5494)
			(drill 1.0414)
			(layers "*.Cu" "*.Mask")
			(remove_unused_layers no)
			(net "GND")
		)
		(pad "2" thru_hole circle
			(at -9.499999 10.449999 270)
			(size 1.5494 1.5494)
			(drill 1.0414)
			(layers "*.Cu" "*.Mask")
			(remove_unused_layers no)
			(net "GND")
		)
		(pad "3" thru_hole circle
			(at -9.499999 19.449999 270)
			(size 1.5494 1.5494)
			(drill 1.0414)
			(layers "*.Cu" "*.Mask")
			(remove_unused_layers no)
			(net "GND")
		)
		(pad "4" thru_hole circle
			(at -9.499999 28.449999 270)
			(size 1.5494 1.5494)
			(drill 1.0414)
			(layers "*.Cu" "*.Mask")
			(remove_unused_layers no)
			(net "GND")
		)
		(pad "5" thru_hole circle
			(at -9.499999 37.449999 270)
			(size 1.5494 1.5494)
			(drill 1.0414)
			(layers "*.Cu" "*.Mask")
			(remove_unused_layers no)
			(net "GND")
		)
		(pad "6" thru_hole circle
			(at -5 -7.75 270)
			(size 1.5494 1.5494)
			(drill 1.0414)
			(layers "*.Cu" "*.Mask")
			(remove_unused_layers no)
			(net "GND")
		)
		(pad "7" thru_hole circle
			(at 2.200001 -7.75 270)
			(size 1.5494 1.5494)
			(drill 1.0414)
			(layers "*.Cu" "*.Mask")
			(remove_unused_layers no)
			(net "GND")
		)
		(pad "8" thru_hole circle
			(at 9.499999 -4.750001 270)
			(size 1.5494 1.5494)
			(drill 1.0414)
			(layers "*.Cu" "*.Mask")
			(remove_unused_layers no)
			(net "GND")
		)
		(pad "9" thru_hole circle
			(at 9.499999 5.950001 270)
			(size 1.5494 1.5494)
			(drill 1.0414)
			(layers "*.Cu" "*.Mask")
			(remove_unused_layers no)
			(net "GND")
		)
		(pad "10" thru_hole circle
			(at 9.499999 14.950001 270)
			(size 1.5494 1.5494)
			(drill 1.0414)
			(layers "*.Cu" "*.Mask")
			(remove_unused_layers no)
			(net "GND")
		)
		(pad "11" thru_hole circle
			(at 9.499999 23.95 270)
			(size 1.5494 1.5494)
			(drill 1.0414)
			(layers "*.Cu" "*.Mask")
			(remove_unused_layers no)
			(net "GND")
		)
		(pad "12" thru_hole circle
			(at 9.499999 32.95 270)
			(size 1.5494 1.5494)
			(drill 1.0414)
			(layers "*.Cu" "*.Mask")
			(remove_unused_layers no)
			(net "GND")
		)
	)
	(footprint ""
		(layer "F.Cu")
		(at -286.893 45.6946)
		(property "Reference" "FS1"
			(at 0.127 1.0795 0)
			(unlocked yes)
			(layer "F.SilkS")
			(effects
				(font
					(size 0.762 0.5334)
					(thickness 0.1016)
				)
			)
		)
		(property "Value" ""
			(at 0 0 0)
			(layer "F.Fab")
			(effects
				(font
					(size 1.27 1.27)
				)
			)
		)
		(duplicate_pad_numbers_are_jumpers no)
		(fp_poly
			(pts
				(xy -1.002101 0.504) (xy -1.002101 -0.503999) (xy 1.002101 -0.503999) (xy 1.002101 0.504)
			)
			(stroke
				(width 0)
				(type default)
			)
			(fill no)
			(layer "F.CrtYd")
		)
		(fp_line
			(start -0.499999 -0.249999)
			(end -0.499999 0.25)
			(stroke
				(width 0.1)
				(type default)
			)
			(layer "F.Fab")
		)
		(fp_line
			(start -0.499999 0.25)
			(end 0.499999 0.25)
			(stroke
				(width 0.1)
				(type default)
			)
			(layer "F.Fab")
		)
		(fp_line
			(start 0.499999 -0.249999)
			(end -0.499999 -0.249999)
			(stroke
				(width 0.1)
				(type default)
			)
			(layer "F.Fab")
		)
		(fp_line
			(start 0.499999 0.25)
			(end 0.499999 -0.249999)
			(stroke
				(width 0.1)
				(type default)
			)
			(layer "F.Fab")
		)
		(pad "1" smd rect
			(at -0.459999 0 90)
			(size 0.508 0.5842)
			(layers "F.Cu" "F.Mask" "F.Paste")
			(net "P3V3_B1_QSFP")
		)
		(pad "2" smd rect
			(at 0.459999 0 90)
			(size 0.508 0.5842)
			(layers "F.Cu" "F.Mask" "F.Paste")
			(net "UNNAMED_4_FERRITE_I148_A")
		)
	)
	(footprint ""
		(layer "F.Cu")
		(at -267.012001 13.424002)
		(property "Reference" "R74"
			(at 3.154261 0.017678 0)
			(unlocked yes)
			(layer "F.SilkS")
			(effects
				(font
					(size 0.762 0.5334)
					(thickness 0.1016)
				)
			)
		)
		(property "Value" ""
			(at 0 0 0)
			(layer "F.Fab")
			(effects
				(font
					(size 1.27 1.27)
				)
			)
		)
		(duplicate_pad_numbers_are_jumpers no)
		(fp_line
			(start 0 -0.381)
			(end 0 0.381)
			(stroke
				(width 0.127)
				(type default)
			)
			(layer "F.SilkS")
		)
		(fp_poly
			(pts
				(xy 1.255601 0.656399) (xy -1.255601 0.656399) (xy -1.255601 -0.6564) (xy 1.255601 -0.6564)
			)
			(stroke
				(width 0)
				(type default)
			)
			(fill no)
			(layer "F.CrtYd")
		)
		(fp_line
			(start -0.800001 -0.4)
			(end -0.800001 0.399999)
			(stroke
				(width 0.1)
				(type default)
			)
			(layer "F.Fab")
		)
		(fp_line
			(start -0.800001 0.399999)
			(end 0.800001 0.399999)
			(stroke
				(width 0.1)
				(type default)
			)
			(layer "F.Fab")
		)
		(fp_line
			(start 0.800001 -0.4)
			(end -0.800001 -0.4)
			(stroke
				(width 0.1)
				(type default)
			)
			(layer "F.Fab")
		)
		(fp_line
			(start 0.800001 0.399999)
			(end 0.800001 -0.4)
			(stroke
				(width 0.1)
				(type default)
			)
			(layer "F.Fab")
		)
		(pad "1" smd rect
			(at -0.650001 0)
			(size 0.7112 0.8128)
			(layers "F.Cu" "F.Mask" "F.Paste")
			(net "P3V3_40G_B1_VCC1")
		)
		(pad "2" smd rect
			(at 0.650001 0 180)
			(size 0.7112 0.8128)
			(layers "F.Cu" "F.Mask" "F.Paste")
			(net "P3V3_B1_QSFP")
		)
	)
	(footprint ""
		(layer "F.Cu")
		(at -336.423 4.9276 -90)
		(property "Reference" "R9"
			(at 1.82626 -1.00838 90)
			(unlocked yes)
			(layer "F.SilkS")
			(effects
				(font
					(size 0.762 0.5334)
					(thickness 0.1016)
				)
			)
		)
		(property "Value" ""
			(at 0 0 270)
			(layer "F.Fab")
			(effects
				(font
					(size 1.27 1.27)
				)
			)
		)
		(duplicate_pad_numbers_are_jumpers no)
		(fp_line
			(start 0 -0.381)
			(end 0 0.381)
			(stroke
				(width 0.127)
				(type default)
			)
			(layer "F.SilkS")
		)
		(fp_poly
			(pts
				(xy 1.255601 0.6564) (xy -1.255601 0.6564) (xy -1.255601 -0.656399) (xy 1.255601 -0.656399)
			)
			(stroke
				(width 0)
				(type default)
			)
			(fill no)
			(layer "F.CrtYd")
		)
		(fp_line
			(start -0.800001 0.399999)
			(end 0.800001 0.399999)
			(stroke
				(width 0.1)
				(type default)
			)
			(layer "F.Fab")
		)
		(fp_line
			(start 0.800001 0.399999)
			(end 0.800001 -0.399999)
			(stroke
				(width 0.1)
				(type default)
			)
			(layer "F.Fab")
		)
		(fp_line
			(start -0.800001 -0.399999)
			(end -0.800001 0.399999)
			(stroke
				(width 0.1)
				(type default)
			)
			(layer "F.Fab")
		)
		(fp_line
			(start 0.800001 -0.399999)
			(end -0.800001 -0.399999)
			(stroke
				(width 0.1)
				(type default)
			)
			(layer "F.Fab")
		)
		(pad "1" smd rect
			(at -0.650001 0 270)
			(size 0.7112 0.8128)
			(layers "F.Cu" "F.Mask" "F.Paste")
			(net "UNNAMED_4_1X2HDR_I81_IO")
		)
		(pad "2" smd rect
			(at 0.650001 0 90)
			(size 0.7112 0.8128)
			(layers "F.Cu" "F.Mask" "F.Paste")
			(net "GND")
		)
	)
	(footprint ""
		(layer "F.Cu")
		(at -270.237801 12.916002 90)
		(property "Reference" "C30"
			(at 0 -0.942899 90)
			(unlocked yes)
			(layer "F.SilkS")
			(effects
				(font
					(size 0.762 0.5334)
					(thickness 0.1016)
				)
			)
		)
		(property "Value" ""
			(at 0 0 90)
			(layer "F.Fab")
			(effects
				(font
					(size 1.27 1.27)
				)
			)
		)
		(duplicate_pad_numbers_are_jumpers no)
		(fp_line
			(start 0 -0.381)
			(end 0 0.381)
			(stroke
				(width 0.127)
				(type default)
			)
			(layer "F.SilkS")
		)
		(fp_poly
			(pts
				(xy 1.2533 0.6564) (xy -1.253299 0.6564) (xy -1.253299 -0.656399) (xy 1.2533 -0.656399)
			)
			(stroke
				(width 0)
				(type default)
			)
			(fill no)
			(layer "F.CrtYd")
		)
		(fp_line
			(start 0.762 -0.381)
			(end -0.762 -0.381)
			(stroke
				(width 0.1)
				(type default)
			)
			(layer "F.Fab")
		)
		(fp_line
			(start -0.762 -0.381)
			(end -0.762 0.381)
			(stroke
				(width 0.1)
				(type default)
			)
			(layer "F.Fab")
		)
		(fp_line
			(start 0.762 0.381)
			(end 0.762 -0.381)
			(stroke
				(width 0.1)
				(type default)
			)
			(layer "F.Fab")
		)
		(fp_line
			(start -0.762 0.381)
			(end 0.762 0.381)
			(stroke
				(width 0.1)
				(type default)
			)
			(layer "F.Fab")
		)
		(pad "1" smd rect
			(at -0.6477 0 90)
			(size 0.7112 0.8128)
			(layers "F.Cu" "F.Mask" "F.Paste")
			(net "P3V3_40G_B1_VCC1")
		)
		(pad "2" smd rect
			(at 0.6477 0 270)
			(size 0.7112 0.8128)
			(layers "F.Cu" "F.Mask" "F.Paste")
			(net "GND")
		)
	)
	(footprint ""
		(layer "F.Cu")
		(at -300.9392 1.4732)
		(property "Reference" "R15"
			(at -3.3528 -0.0381 0)
			(unlocked yes)
			(layer "F.SilkS")
			(effects
				(font
					(size 0.762 0.5334)
					(thickness 0.1016)
				)
			)
		)
		(property "Value" ""
			(at 0 0 0)
			(layer "F.Fab")
			(effects
				(font
					(size 1.27 1.27)
				)
			)
		)
		(duplicate_pad_numbers_are_jumpers no)
		(fp_line
			(start 0 -0.381)
			(end 0 0.381)
			(stroke
				(width 0.127)
				(type default)
			)
			(layer "F.SilkS")
		)
		(fp_poly
			(pts
				(xy 1.255601 0.6564) (xy -1.255601 0.6564) (xy -1.255601 -0.656399) (xy 1.255601 -0.656399)
			)
			(stroke
				(width 0)
				(type default)
			)
			(fill no)
			(layer "F.CrtYd")
		)
		(fp_line
			(start -0.800001 -0.399999)
			(end -0.800001 0.399999)
			(stroke
				(width 0.1)
				(type default)
			)
			(layer "F.Fab")
		)
		(fp_line
			(start -0.800001 0.399999)
			(end 0.800001 0.399999)
			(stroke
				(width 0.1)
				(type default)
			)
			(layer "F.Fab")
		)
		(fp_line
			(start 0.800001 -0.399999)
			(end -0.800001 -0.399999)
			(stroke
				(width 0.1)
				(type default)
			)
			(layer "F.Fab")
		)
		(fp_line
			(start 0.800001 0.399999)
			(end 0.800001 -0.399999)
			(stroke
				(width 0.1)
				(type default)
			)
			(layer "F.Fab")
		)
		(pad "1" smd rect
			(at -0.650001 0)
			(size 0.7112 0.8128)
			(layers "F.Cu" "F.Mask" "F.Paste")
			(net "ETH10G_B1_PRES_N")
		)
		(pad "2" smd rect
			(at 0.650001 0 180)
			(size 0.7112 0.8128)
			(layers "F.Cu" "F.Mask" "F.Paste")
			(net "ETH10G_B1_MOD_ABS")
		)
	)
	(footprint ""
		(layer "F.Cu")
		(at -300.9392 8.8646 180)
		(property "Reference" "R5"
			(at 3.6068 -0.0635 0)
			(unlocked yes)
			(layer "F.SilkS")
			(effects
				(font
					(size 0.762 0.5334)
					(thickness 0.1016)
				)
			)
		)
		(property "Value" ""
			(at 0 0 180)
			(layer "F.Fab")
			(effects
				(font
					(size 1.27 1.27)
				)
			)
		)
		(duplicate_pad_numbers_are_jumpers no)
		(fp_line
			(start 0 -0.381)
			(end 0 0.381)
			(stroke
				(width 0.127)
				(type default)
			)
			(layer "F.SilkS")
		)
		(fp_poly
			(pts
				(xy 1.255601 0.656399) (xy -1.255601 0.656399) (xy -1.255601 -0.6564) (xy 1.255601 -0.6564)
			)
			(stroke
				(width 0)
				(type default)
			)
			(fill no)
			(layer "F.CrtYd")
		)
		(fp_line
			(start 0.800001 0.399999)
			(end 0.800001 -0.399999)
			(stroke
				(width 0.1)
				(type default)
			)
			(layer "F.Fab")
		)
		(fp_line
			(start 0.800001 -0.399999)
			(end -0.800001 -0.399999)
			(stroke
				(width 0.1)
				(type default)
			)
			(layer "F.Fab")
		)
		(fp_line
			(start -0.800001 0.399999)
			(end 0.800001 0.399999)
			(stroke
				(width 0.1)
				(type default)
			)
			(layer "F.Fab")
		)
		(fp_line
			(start -0.800001 -0.399999)
			(end -0.800001 0.399999)
			(stroke
				(width 0.1)
				(type default)
			)
			(layer "F.Fab")
		)
		(pad "1" smd rect
			(at -0.650001 0 180)
			(size 0.7112 0.8128)
			(layers "F.Cu" "F.Mask" "F.Paste")
			(net "SKU_B1_ID1")
		)
		(pad "2" smd rect
			(at 0.650001 0)
			(size 0.7112 0.8128)
			(layers "F.Cu" "F.Mask" "F.Paste")
			(net "GND")
		)
	)
	(footprint ""
		(layer "F.Cu")
		(at -44.996001 11.519002 -90)
		(property "Reference" "FS7"
			(at 0.170078 -1.749961 90)
			(unlocked yes)
			(layer "F.SilkS")
			(effects
				(font
					(size 0.762 0.5334)
					(thickness 0.1016)
				)
			)
		)
		(property "Value" ""
			(at 0 0 270)
			(layer "F.Fab")
			(effects
				(font
					(size 1.27 1.27)
				)
			)
		)
		(duplicate_pad_numbers_are_jumpers no)
		(fp_poly
			(pts
				(xy -1.002102 0.503999) (xy -1.002102 -0.504) (xy 1.002101 -0.504) (xy 1.002101 0.503999)
			)
			(stroke
				(width 0)
				(type default)
			)
			(fill no)
			(layer "F.CrtYd")
		)
		(fp_line
			(start -0.499999 0.249999)
			(end 0.499999 0.249999)
			(stroke
				(width 0.1)
				(type default)
			)
			(layer "F.Fab")
		)
		(fp_line
			(start 0.499999 0.249999)
			(end 0.499999 -0.25)
			(stroke
				(width 0.1)
				(type default)
			)
			(layer "F.Fab")
		)
		(fp_line
			(start -0.499999 -0.25)
			(end -0.499999 0.249999)
			(stroke
				(width 0.1)
				(type default)
			)
			(layer "F.Fab")
		)
		(fp_line
			(start 0.499999 -0.25)
			(end -0.499999 -0.25)
			(stroke
				(width 0.1)
				(type default)
			)
			(layer "F.Fab")
		)
		(pad "1" smd rect
			(at -0.459999 0)
			(size 0.508 0.5842)
			(layers "F.Cu" "F.Mask" "F.Paste")
			(net "UNNAMED_8_FERRITE_I47_B")
		)
		(pad "2" smd rect
			(at 0.459999 0)
			(size 0.508 0.5842)
			(layers "F.Cu" "F.Mask" "F.Paste")
			(net "P3V3_B2_QSFP")
		)
	)
)
